(kicad_pcb
	(version 20260206)
	(generator "pcbnew")
	(generator_version "10.0")
	(general
		(thickness 1.6)
		(legacy_teardrops no)
	)
	(paper "A4")
	(title_block
		(title "9052_F0T_PDB_Converter_Brick_F_V03_1208_1600_OCP.brd")
		(comment 1 "Grand Teton / footprints 535-540 of 578")
	)
	(layers
		(0 "F.Cu" signal "TOP")
		(4 "In1.Cu" signal "GND")
		(6 "In2.Cu" signal "IN1")
		(8 "In3.Cu" signal "GND1")
		(10 "In4.Cu" signal "VCC")
		(12 "In5.Cu" signal "VCC1")
		(14 "In6.Cu" signal "GND2")
		(16 "In7.Cu" signal "IN2")
		(18 "In8.Cu" signal "GND3")
		(2 "B.Cu" signal "BOTTOM")
		(9 "F.Adhes" user "F.Adhesive")
		(11 "B.Adhes" user "B.Adhesive")
		(13 "F.Paste" user "Package Geometry/Pastemask Top")
		(15 "B.Paste" user "Package Geometry/Pastemask Bottom")
		(5 "F.SilkS" user "Ref Des/Silkscreen Top")
		(7 "B.SilkS" user "Ref Des/Silkscreen Bottom")
		(1 "F.Mask" user "Board Geometry/Soldermask Top")
		(3 "B.Mask" user "Board Geometry/Soldermask Bottom")
		(17 "Dwgs.User" user "User.Drawings")
		(19 "Cmts.User" user "User.Comments")
		(21 "Eco1.User" user "User.Eco1")
		(23 "Eco2.User" user "User.Eco2")
		(25 "Edge.Cuts" user "Board Geometry/Outline")
		(27 "Margin" user)
		(31 "F.CrtYd" user "Package Geometry/Place Bound Top")
		(29 "B.CrtYd" user "Package Geometry/Place Bound Bottom")
		(35 "F.Fab" user "Ref Des/Assembly Top")
		(33 "B.Fab" user "Ref Des/Assembly Bottom")
	)
	(footprint ""
		(layer "B.Cu")
		(at 276.733 -42.545)
		(property "Reference" "PR37"
			(at 0 0 0)
			(layer "B.SilkS")
			(hide yes)
			(effects
				(font
					(size 1.27 1.27)
				)
				(justify mirror)
			)
		)
		(property "Value" ""
			(at 0 0 0)
			(layer "B.Fab")
			(effects
				(font
					(size 1.27 1.27)
				)
				(justify mirror)
			)
		)
		(duplicate_pad_numbers_are_jumpers no)
		(fp_line
			(start -0.7874 -0.4064)
			(end -0.7874 0.4064)
			(stroke
				(width 0.1524)
				(type default)
			)
			(layer "B.SilkS")
		)
		(fp_line
			(start -0.7874 0.4064)
			(end 0.7874 0.4064)
			(stroke
				(width 0.1524)
				(type default)
			)
			(layer "B.SilkS")
		)
		(fp_line
			(start 0.7874 -0.4064)
			(end -0.7874 -0.4064)
			(stroke
				(width 0.1524)
				(type default)
			)
			(layer "B.SilkS")
		)
		(fp_line
			(start 0.7874 0.4064)
			(end 0.7874 -0.4064)
			(stroke
				(width 0.1524)
				(type default)
			)
			(layer "B.SilkS")
		)
		(fp_line
			(start -0.67945 -0.3048)
			(end -0.67945 0.3048)
			(stroke
				(width 0.1)
				(type default)
			)
			(layer "B.Fab")
		)
		(fp_line
			(start -0.67945 0.3048)
			(end -0.120396 0.3048)
			(stroke
				(width 0.1)
				(type default)
			)
			(layer "B.Fab")
		)
		(fp_line
			(start -0.12065 -0.3048)
			(end -0.67945 -0.3048)
			(stroke
				(width 0.1)
				(type default)
			)
			(layer "B.Fab")
		)
		(fp_line
			(start -0.12065 -0.2794)
			(end -0.12065 -0.3048)
			(stroke
				(width 0.1)
				(type default)
			)
			(layer "B.Fab")
		)
		(fp_line
			(start -0.120396 0.2794)
			(end 0.12065 0.2794)
			(stroke
				(width 0.1)
				(type default)
			)
			(layer "B.Fab")
		)
		(fp_line
			(start -0.120396 0.3048)
			(end -0.120396 0.2794)
			(stroke
				(width 0.1)
				(type default)
			)
			(layer "B.Fab")
		)
		(fp_line
			(start 0.12065 -0.305054)
			(end 0.12065 -0.2794)
			(stroke
				(width 0.1)
				(type default)
			)
			(layer "B.Fab")
		)
		(fp_line
			(start 0.12065 -0.2794)
			(end -0.12065 -0.2794)
			(stroke
				(width 0.1)
				(type default)
			)
			(layer "B.Fab")
		)
		(fp_line
			(start 0.12065 0.2794)
			(end 0.12065 0.3048)
			(stroke
				(width 0.1)
				(type default)
			)
			(layer "B.Fab")
		)
		(fp_line
			(start 0.12065 0.3048)
			(end 0.67945 0.3048)
			(stroke
				(width 0.1)
				(type default)
			)
			(layer "B.Fab")
		)
		(fp_line
			(start 0.67945 -0.305054)
			(end 0.12065 -0.305054)
			(stroke
				(width 0.1)
				(type default)
			)
			(layer "B.Fab")
		)
		(fp_line
			(start 0.67945 0.3048)
			(end 0.67945 -0.305054)
			(stroke
				(width 0.1)
				(type default)
			)
			(layer "B.Fab")
		)
		(pad "1" smd circle
			(at 0.40005 0 180)
			(size 0 0)
			(layers "B.Cu" "B.Mask" "B.Paste")
			(net "P52V_HS1_EFAULT")
		)
		(pad "2" smd circle
			(at -0.40005 0 180)
			(size 0 0)
			(layers "B.Cu" "B.Mask" "B.Paste")
			(net "GND_FIELD_SIGNAL")
		)
	)
	(footprint ""
		(layer "B.Cu")
		(at 212.344 -84.455 180)
		(property "Reference" "R189"
			(at 0 0 0)
			(layer "B.SilkS")
			(hide yes)
			(effects
				(font
					(size 1.27 1.27)
				)
				(justify mirror)
			)
		)
		(property "Value" ""
			(at 0 0 0)
			(layer "B.Fab")
			(effects
				(font
					(size 1.27 1.27)
				)
				(justify mirror)
			)
		)
		(duplicate_pad_numbers_are_jumpers no)
		(fp_line
			(start 0.7874 0.4064)
			(end 0.7874 -0.4064)
			(stroke
				(width 0.1524)
				(type default)
			)
			(layer "B.SilkS")
		)
		(fp_line
			(start 0.7874 -0.4064)
			(end -0.7874 -0.4064)
			(stroke
				(width 0.1524)
				(type default)
			)
			(layer "B.SilkS")
		)
		(fp_line
			(start -0.7874 0.4064)
			(end 0.7874 0.4064)
			(stroke
				(width 0.1524)
				(type default)
			)
			(layer "B.SilkS")
		)
		(fp_line
			(start -0.7874 -0.4064)
			(end -0.7874 0.4064)
			(stroke
				(width 0.1524)
				(type default)
			)
			(layer "B.SilkS")
		)
		(fp_line
			(start 0.67945 0.3048)
			(end 0.67945 -0.305054)
			(stroke
				(width 0.1)
				(type default)
			)
			(layer "B.Fab")
		)
		(fp_line
			(start 0.67945 -0.305054)
			(end 0.12065 -0.305054)
			(stroke
				(width 0.1)
				(type default)
			)
			(layer "B.Fab")
		)
		(fp_line
			(start 0.12065 0.3048)
			(end 0.67945 0.3048)
			(stroke
				(width 0.1)
				(type default)
			)
			(layer "B.Fab")
		)
		(fp_line
			(start 0.12065 0.2794)
			(end 0.12065 0.3048)
			(stroke
				(width 0.1)
				(type default)
			)
			(layer "B.Fab")
		)
		(fp_line
			(start 0.12065 -0.2794)
			(end -0.12065 -0.2794)
			(stroke
				(width 0.1)
				(type default)
			)
			(layer "B.Fab")
		)
		(fp_line
			(start 0.12065 -0.305054)
			(end 0.12065 -0.2794)
			(stroke
				(width 0.1)
				(type default)
			)
			(layer "B.Fab")
		)
		(fp_line
			(start -0.120396 0.3048)
			(end -0.120396 0.2794)
			(stroke
				(width 0.1)
				(type default)
			)
			(layer "B.Fab")
		)
		(fp_line
			(start -0.120396 0.2794)
			(end 0.12065 0.2794)
			(stroke
				(width 0.1)
				(type default)
			)
			(layer "B.Fab")
		)
		(fp_line
			(start -0.12065 -0.2794)
			(end -0.12065 -0.3048)
			(stroke
				(width 0.1)
				(type default)
			)
			(layer "B.Fab")
		)
		(fp_line
			(start -0.12065 -0.3048)
			(end -0.67945 -0.3048)
			(stroke
				(width 0.1)
				(type default)
			)
			(layer "B.Fab")
		)
		(fp_line
			(start -0.67945 0.3048)
			(end -0.120396 0.3048)
			(stroke
				(width 0.1)
				(type default)
			)
			(layer "B.Fab")
		)
		(fp_line
			(start -0.67945 -0.3048)
			(end -0.67945 0.3048)
			(stroke
				(width 0.1)
				(type default)
			)
			(layer "B.Fab")
		)
		(pad "1" smd circle
			(at 0.40005 0)
			(size 0 0)
			(layers "B.Cu" "B.Mask" "B.Paste")
			(net "PWRGD_GPU_HSC")
		)
		(pad "2" smd circle
			(at -0.40005 0)
			(size 0 0)
			(layers "B.Cu" "B.Mask" "B.Paste")
			(net "PWRGD_GPU_HSC_BUF_R")
		)
	)
	(footprint ""
		(layer "B.Cu")
		(at 98.806 -77.47 180)
		(property "Reference" "C57"
			(at 0 0 0)
			(layer "B.SilkS")
			(hide yes)
			(effects
				(font
					(size 1.27 1.27)
				)
				(justify mirror)
			)
		)
		(property "Value" ""
			(at 0 0 0)
			(layer "B.Fab")
			(effects
				(font
					(size 1.27 1.27)
				)
				(justify mirror)
			)
		)
		(duplicate_pad_numbers_are_jumpers no)
		(fp_line
			(start 0.7874 0.4064)
			(end 0.7874 -0.4064)
			(stroke
				(width 0.1524)
				(type default)
			)
			(layer "B.SilkS")
		)
		(fp_line
			(start 0.7874 -0.4064)
			(end -0.7874 -0.4064)
			(stroke
				(width 0.1524)
				(type default)
			)
			(layer "B.SilkS")
		)
		(fp_line
			(start -0.7874 0.4064)
			(end 0.7874 0.4064)
			(stroke
				(width 0.1524)
				(type default)
			)
			(layer "B.SilkS")
		)
		(fp_line
			(start -0.7874 -0.4064)
			(end -0.7874 0.4064)
			(stroke
				(width 0.1524)
				(type default)
			)
			(layer "B.SilkS")
		)
		(fp_line
			(start 0.67945 0.3048)
			(end 0.67945 -0.305054)
			(stroke
				(width 0.1)
				(type default)
			)
			(layer "B.Fab")
		)
		(fp_line
			(start 0.67945 -0.305054)
			(end 0.12065 -0.305054)
			(stroke
				(width 0.1)
				(type default)
			)
			(layer "B.Fab")
		)
		(fp_line
			(start 0.12065 0.3048)
			(end 0.67945 0.3048)
			(stroke
				(width 0.1)
				(type default)
			)
			(layer "B.Fab")
		)
		(fp_line
			(start 0.12065 0.2794)
			(end 0.12065 0.3048)
			(stroke
				(width 0.1)
				(type default)
			)
			(layer "B.Fab")
		)
		(fp_line
			(start 0.12065 -0.2794)
			(end -0.12065 -0.2794)
			(stroke
				(width 0.1)
				(type default)
			)
			(layer "B.Fab")
		)
		(fp_line
			(start 0.12065 -0.305054)
			(end 0.12065 -0.2794)
			(stroke
				(width 0.1)
				(type default)
			)
			(layer "B.Fab")
		)
		(fp_line
			(start -0.120396 0.3048)
			(end -0.120396 0.2794)
			(stroke
				(width 0.1)
				(type default)
			)
			(layer "B.Fab")
		)
		(fp_line
			(start -0.120396 0.2794)
			(end 0.12065 0.2794)
			(stroke
				(width 0.1)
				(type default)
			)
			(layer "B.Fab")
		)
		(fp_line
			(start -0.12065 -0.2794)
			(end -0.12065 -0.3048)
			(stroke
				(width 0.1)
				(type default)
			)
			(layer "B.Fab")
		)
		(fp_line
			(start -0.12065 -0.3048)
			(end -0.67945 -0.3048)
			(stroke
				(width 0.1)
				(type default)
			)
			(layer "B.Fab")
		)
		(fp_line
			(start -0.67945 0.3048)
			(end -0.120396 0.3048)
			(stroke
				(width 0.1)
				(type default)
			)
			(layer "B.Fab")
		)
		(fp_line
			(start -0.67945 -0.3048)
			(end -0.67945 0.3048)
			(stroke
				(width 0.1)
				(type default)
			)
			(layer "B.Fab")
		)
		(pad "1" smd circle
			(at 0.40005 0)
			(size 0 0)
			(layers "B.Cu" "B.Mask" "B.Paste")
			(net "SMB_P52V_VPDB_SDA")
		)
		(pad "2" smd circle
			(at -0.40005 0)
			(size 0 0)
			(layers "B.Cu" "B.Mask" "B.Paste")
			(net "GND")
		)
	)
	(footprint ""
		(layer "B.Cu")
		(at 229.87 -70.993 -90)
		(property "Reference" "C17"
			(at 0 0 90)
			(layer "B.SilkS")
			(hide yes)
			(effects
				(font
					(size 1.27 1.27)
				)
				(justify mirror)
			)
		)
		(property "Value" ""
			(at 0 0 90)
			(layer "B.Fab")
			(effects
				(font
					(size 1.27 1.27)
				)
				(justify mirror)
			)
		)
		(duplicate_pad_numbers_are_jumpers no)
		(fp_line
			(start -0.7874 0.4064)
			(end 0.7874 0.4064)
			(stroke
				(width 0.1524)
				(type default)
			)
			(layer "B.SilkS")
		)
		(fp_line
			(start 0.7874 0.4064)
			(end 0.7874 -0.4064)
			(stroke
				(width 0.1524)
				(type default)
			)
			(layer "B.SilkS")
		)
		(fp_line
			(start -0.7874 -0.4064)
			(end -0.7874 0.4064)
			(stroke
				(width 0.1524)
				(type default)
			)
			(layer "B.SilkS")
		)
		(fp_line
			(start 0.7874 -0.4064)
			(end -0.7874 -0.4064)
			(stroke
				(width 0.1524)
				(type default)
			)
			(layer "B.SilkS")
		)
		(fp_line
			(start -0.67945 0.3048)
			(end -0.120396 0.3048)
			(stroke
				(width 0.1)
				(type default)
			)
			(layer "B.Fab")
		)
		(fp_line
			(start -0.120396 0.3048)
			(end -0.120396 0.2794)
			(stroke
				(width 0.1)
				(type default)
			)
			(layer "B.Fab")
		)
		(fp_line
			(start 0.12065 0.3048)
			(end 0.67945 0.3048)
			(stroke
				(width 0.1)
				(type default)
			)
			(layer "B.Fab")
		)
		(fp_line
			(start 0.67945 0.3048)
			(end 0.67945 -0.305054)
			(stroke
				(width 0.1)
				(type default)
			)
			(layer "B.Fab")
		)
		(fp_line
			(start -0.120396 0.2794)
			(end 0.12065 0.2794)
			(stroke
				(width 0.1)
				(type default)
			)
			(layer "B.Fab")
		)
		(fp_line
			(start 0.12065 0.2794)
			(end 0.12065 0.3048)
			(stroke
				(width 0.1)
				(type default)
			)
			(layer "B.Fab")
		)
		(fp_line
			(start -0.12065 -0.2794)
			(end -0.12065 -0.3048)
			(stroke
				(width 0.1)
				(type default)
			)
			(layer "B.Fab")
		)
		(fp_line
			(start 0.12065 -0.2794)
			(end -0.12065 -0.2794)
			(stroke
				(width 0.1)
				(type default)
			)
			(layer "B.Fab")
		)
		(fp_line
			(start -0.67945 -0.3048)
			(end -0.67945 0.3048)
			(stroke
				(width 0.1)
				(type default)
			)
			(layer "B.Fab")
		)
		(fp_line
			(start -0.12065 -0.3048)
			(end -0.67945 -0.3048)
			(stroke
				(width 0.1)
				(type default)
			)
			(layer "B.Fab")
		)
		(fp_line
			(start 0.12065 -0.305054)
			(end 0.12065 -0.2794)
			(stroke
				(width 0.1)
				(type default)
			)
			(layer "B.Fab")
		)
		(fp_line
			(start 0.67945 -0.305054)
			(end 0.12065 -0.305054)
			(stroke
				(width 0.1)
				(type default)
			)
			(layer "B.Fab")
		)
		(pad "1" smd circle
			(at 0.40005 0 90)
			(size 0 0)
			(layers "B.Cu" "B.Mask" "B.Paste")
			(net "FAN_PWR_R_EN")
		)
		(pad "2" smd circle
			(at -0.40005 0 90)
			(size 0 0)
			(layers "B.Cu" "B.Mask" "B.Paste")
			(net "GND")
		)
	)
	(footprint ""
		(layer "B.Cu")
		(at 207.264 -69.723 -90)
		(property "Reference" "R117"
			(at 0 0 90)
			(layer "B.SilkS")
			(hide yes)
			(effects
				(font
					(size 1.27 1.27)
				)
				(justify mirror)
			)
		)
		(property "Value" ""
			(at 0 0 90)
			(layer "B.Fab")
			(effects
				(font
					(size 1.27 1.27)
				)
				(justify mirror)
			)
		)
		(duplicate_pad_numbers_are_jumpers no)
		(fp_line
			(start -0.7874 0.4064)
			(end 0.7874 0.4064)
			(stroke
				(width 0.1524)
				(type default)
			)
			(layer "B.SilkS")
		)
		(fp_line
			(start 0.7874 0.4064)
			(end 0.7874 -0.4064)
			(stroke
				(width 0.1524)
				(type default)
			)
			(layer "B.SilkS")
		)
		(fp_line
			(start -0.7874 -0.4064)
			(end -0.7874 0.4064)
			(stroke
				(width 0.1524)
				(type default)
			)
			(layer "B.SilkS")
		)
		(fp_line
			(start 0.7874 -0.4064)
			(end -0.7874 -0.4064)
			(stroke
				(width 0.1524)
				(type default)
			)
			(layer "B.SilkS")
		)
		(fp_line
			(start -0.67945 0.3048)
			(end -0.120396 0.3048)
			(stroke
				(width 0.1)
				(type default)
			)
			(layer "B.Fab")
		)
		(fp_line
			(start -0.120396 0.3048)
			(end -0.120396 0.2794)
			(stroke
				(width 0.1)
				(type default)
			)
			(layer "B.Fab")
		)
		(fp_line
			(start 0.12065 0.3048)
			(end 0.67945 0.3048)
			(stroke
				(width 0.1)
				(type default)
			)
			(layer "B.Fab")
		)
		(fp_line
			(start 0.67945 0.3048)
			(end 0.67945 -0.305054)
			(stroke
				(width 0.1)
				(type default)
			)
			(layer "B.Fab")
		)
		(fp_line
			(start -0.120396 0.2794)
			(end 0.12065 0.2794)
			(stroke
				(width 0.1)
				(type default)
			)
			(layer "B.Fab")
		)
		(fp_line
			(start 0.12065 0.2794)
			(end 0.12065 0.3048)
			(stroke
				(width 0.1)
				(type default)
			)
			(layer "B.Fab")
		)
		(fp_line
			(start -0.12065 -0.2794)
			(end -0.12065 -0.3048)
			(stroke
				(width 0.1)
				(type default)
			)
			(layer "B.Fab")
		)
		(fp_line
			(start 0.12065 -0.2794)
			(end -0.12065 -0.2794)
			(stroke
				(width 0.1)
				(type default)
			)
			(layer "B.Fab")
		)
		(fp_line
			(start -0.67945 -0.3048)
			(end -0.67945 0.3048)
			(stroke
				(width 0.1)
				(type default)
			)
			(layer "B.Fab")
		)
		(fp_line
			(start -0.12065 -0.3048)
			(end -0.67945 -0.3048)
			(stroke
				(width 0.1)
				(type default)
			)
			(layer "B.Fab")
		)
		(fp_line
			(start 0.12065 -0.305054)
			(end 0.12065 -0.2794)
			(stroke
				(width 0.1)
				(type default)
			)
			(layer "B.Fab")
		)
		(fp_line
			(start 0.67945 -0.305054)
			(end 0.12065 -0.305054)
			(stroke
				(width 0.1)
				(type default)
			)
			(layer "B.Fab")
		)
		(pad "1" smd circle
			(at 0.40005 0 90)
			(size 0 0)
			(layers "B.Cu" "B.Mask" "B.Paste")
			(net "SMB_VPDB_MISC_SDA")
		)
		(pad "2" smd circle
			(at -0.40005 0 90)
			(size 0 0)
			(layers "B.Cu" "B.Mask" "B.Paste")
			(net "SMB_VPDB_IOEXP_SDA")
		)
	)
	(footprint ""
		(layer "B.Cu")
		(at 231.013 -84.836 -90)
		(property "Reference" "R142"
			(at 0 0 90)
			(layer "B.SilkS")
			(hide yes)
			(effects
				(font
					(size 1.27 1.27)
				)
				(justify mirror)
			)
		)
		(property "Value" ""
			(at 0 0 90)
			(layer "B.Fab")
			(effects
				(font
					(size 1.27 1.27)
				)
				(justify mirror)
			)
		)
		(duplicate_pad_numbers_are_jumpers no)
		(fp_line
			(start -0.7874 0.4064)
			(end 0.7874 0.4064)
			(stroke
				(width 0.1524)
				(type default)
			)
			(layer "B.SilkS")
		)
		(fp_line
			(start 0.7874 0.4064)
			(end 0.7874 -0.4064)
			(stroke
				(width 0.1524)
				(type default)
			)
			(layer "B.SilkS")
		)
		(fp_line
			(start -0.7874 -0.4064)
			(end -0.7874 0.4064)
			(stroke
				(width 0.1524)
				(type default)
			)
			(layer "B.SilkS")
		)
		(fp_line
			(start 0.7874 -0.4064)
			(end -0.7874 -0.4064)
			(stroke
				(width 0.1524)
				(type default)
			)
			(layer "B.SilkS")
		)
		(fp_line
			(start -0.67945 0.3048)
			(end -0.120396 0.3048)
			(stroke
				(width 0.1)
				(type default)
			)
			(layer "B.Fab")
		)
		(fp_line
			(start -0.120396 0.3048)
			(end -0.120396 0.2794)
			(stroke
				(width 0.1)
				(type default)
			)
			(layer "B.Fab")
		)
		(fp_line
			(start 0.12065 0.3048)
			(end 0.67945 0.3048)
			(stroke
				(width 0.1)
				(type default)
			)
			(layer "B.Fab")
		)
		(fp_line
			(start 0.67945 0.3048)
			(end 0.67945 -0.305054)
			(stroke
				(width 0.1)
				(type default)
			)
			(layer "B.Fab")
		)
		(fp_line
			(start -0.120396 0.2794)
			(end 0.12065 0.2794)
			(stroke
				(width 0.1)
				(type default)
			)
			(layer "B.Fab")
		)
		(fp_line
			(start 0.12065 0.2794)
			(end 0.12065 0.3048)
			(stroke
				(width 0.1)
				(type default)
			)
			(layer "B.Fab")
		)
		(fp_line
			(start -0.12065 -0.2794)
			(end -0.12065 -0.3048)
			(stroke
				(width 0.1)
				(type default)
			)
			(layer "B.Fab")
		)
		(fp_line
			(start 0.12065 -0.2794)
			(end -0.12065 -0.2794)
			(stroke
				(width 0.1)
				(type default)
			)
			(layer "B.Fab")
		)
		(fp_line
			(start -0.67945 -0.3048)
			(end -0.67945 0.3048)
			(stroke
				(width 0.1)
				(type default)
			)
			(layer "B.Fab")
		)
		(fp_line
			(start -0.12065 -0.3048)
			(end -0.67945 -0.3048)
			(stroke
				(width 0.1)
				(type default)
			)
			(layer "B.Fab")
		)
		(fp_line
			(start 0.12065 -0.305054)
			(end 0.12065 -0.2794)
			(stroke
				(width 0.1)
				(type default)
			)
			(layer "B.Fab")
		)
		(fp_line
			(start 0.67945 -0.305054)
			(end 0.12065 -0.305054)
			(stroke
				(width 0.1)
				(type default)
			)
			(layer "B.Fab")
		)
		(pad "1" smd circle
			(at 0.40005 0 90)
			(size 0 0)
			(layers "B.Cu" "B.Mask" "B.Paste")
			(net "P3V3_AUX")
		)
		(pad "2" smd circle
			(at -0.40005 0 90)
			(size 0 0)
			(layers "B.Cu" "B.Mask" "B.Paste")
			(net "PWRGD_P3V3_AUX_MB_BUF_N")
		)
	)
)
